#ISCELL
  logical_power design_note *
  *
#ISCELL
  mstr_misc dns *
  *
#ISCELL
  pure_quanta quanta_title_block_c *
  *
#ISCELL
  standard offpage *
  page185_i18
#ISCELL
  standard offpage *
  page185_i19
#ISCELL
  standard offpage *
  page185_i20
#ISCELL
  logical_power universal_gnd *
  page185_i22
#CELL
  pure_quanta q_res *
  page185_i24
#CELL
  pure_quanta q_res *
  page185_i26
#ISCELL
  logical_power universal_power *
  page185_i27
#ISCELL
  logical_power universal_gnd *
  page185_i28
#CELL
  pure_quanta q_res *
  page185_i30
#ISCELL
  logical_power universal_power *
  page185_i31
#CELL
  pure_quanta q_res *
  page185_i32
#ISCELL
  logical_power universal_gnd *
  page185_i34
#CELL
  pure_quanta nc7sb3157 *
  page185_i35
#CELL
  pure_quanta q_cap *
  page185_i36
#ISCELL
  logical_power universal_power *
  page185_i37
#ISCELL
  logical_power universal_gnd *
  page185_i38
#CELL
  pure_quanta q_res *
  page185_i39
#ISCELL
  logical_power universal_power *
  page185_i40
#CELL
  pure_quanta q_res *
  page185_i41
#CELL
  pure_quanta q_res *
  page185_i42
#ISCELL
  logical_power universal_gnd *
  page185_i43
#ISCELL
  standard offpage *
  page185_i44
#CELL
  pure_quanta q_res *
  page185_i45
#ISCELL
  standard offpage *
  page185_i46
#CELL
  pure_quanta q_res *
  page185_i47
#CELL
  pure_quanta q_res *
  page185_i49
#CELL
  pure_quanta q_res *
  page185_i50
#CELL
  pure_quanta q_res *
  page185_i51
